(kicad_pcb
	(version 20241229)
	(generator "pcbnew")
	(generator_version "9.0")
	(general
		(thickness 1.61)
		(legacy_teardrops no)
	)
	(paper "A3")
	(title_block
		(title "SO-DIMM DDR5 Tester")
		(date "2025-11-26")
		(rev "1.3.0")
		(comment 9 "footprints 182-186 of 627")
	)
	(layers
		(0 "F.Cu" signal)
		(4 "In1.Cu" power)
		(6 "In2.Cu" mixed)
		(8 "In3.Cu" power)
		(10 "In4.Cu" mixed)
		(12 "In5.Cu" power)
		(14 "In6.Cu" mixed)
		(16 "In7.Cu" power)
		(18 "In8.Cu" power)
		(20 "In9.Cu" mixed)
		(22 "In10.Cu" power)
		(2 "B.Cu" signal)
		(9 "F.Adhes" user "F.Adhesive")
		(11 "B.Adhes" user "B.Adhesive")
		(13 "F.Paste" user)
		(15 "B.Paste" user)
		(5 "F.SilkS" user "F.Silkscreen")
		(7 "B.SilkS" user "B.Silkscreen")
		(1 "F.Mask" user)
		(3 "B.Mask" user)
		(17 "Dwgs.User" user "User.Drawings")
		(19 "Cmts.User" user "User.Comments")
		(21 "Eco1.User" user "User.Eco1")
		(23 "Eco2.User" user "User.Eco2")
		(25 "Edge.Cuts" user)
		(27 "Margin" user)
		(31 "F.CrtYd" user "F.Courtyard")
		(29 "B.CrtYd" user "B.Courtyard")
		(35 "F.Fab" user)
		(33 "B.Fab" user)
	)
	(footprint "antmicro-footprints:Vishay_PowerPAK_1212-8_Single"
		(layer "F.Cu")
		(at 187.870501 133.123 90)
		(descr "PowerPAK 1212-8 Single")
		(tags "Vishay PowerPAK 1212-8 Single")
		(property "Reference" "Q12"
			(at 0 2.883499 90)
			(layer "F.SilkS")
			(effects
				(font
					(size 0.7 0.7)
					(thickness 0.15)
				)
				(justify left bottom)
			)
		)
		(property "Value" "SI7613DN-T1-GE3"
			(at 0 2.7 90)
			(layer "F.Fab")
			(effects
				(font
					(size 0.7 0.7)
					(thickness 0.15)
				)
				(justify left bottom)
			)
		)
		(property "Datasheet" "https://www.vishay.com/docs/64809/si7613dn.pdf"
			(at 0 0 90)
			(layer "F.Fab")
			(hide yes)
			(effects
				(font
					(size 1.27 1.27)
					(thickness 0.15)
				)
			)
		)
		(property "Author" "Antmicro"
			(at 320.993501 -54.747501 0)
			(layer "F.Fab")
			(hide yes)
			(effects
				(font
					(size 1 1)
					(thickness 0.15)
				)
			)
		)
		(property "License" "Apache-2.0"
			(at 320.993501 -54.747501 0)
			(layer "F.Fab")
			(hide yes)
			(effects
				(font
					(size 1 1)
					(thickness 0.15)
				)
			)
		)
		(property "MPN" "SI7613DN-T1-GE3"
			(at 320.993501 -54.747501 0)
			(layer "F.Fab")
			(hide yes)
			(effects
				(font
					(size 1 1)
					(thickness 0.15)
				)
			)
		)
		(property "Manufacturer" "Vishay"
			(at 320.993501 -54.747501 0)
			(layer "F.Fab")
			(hide yes)
			(effects
				(font
					(size 1 1)
					(thickness 0.15)
				)
			)
		)
		(sheetname "/Supply/")
		(sheetfile "supply.kicad_sch")
		(attr smd)
		(fp_line
			(start 1.648 -1.651)
			(end 1.648 -1.317)
			(stroke
				(width 0.15)
				(type solid)
			)
			(layer "F.SilkS")
		)
		(fp_line
			(start -1.651 -1.651)
			(end 1.648 -1.651)
			(stroke
				(width 0.15)
				(type solid)
			)
			(layer "F.SilkS")
		)
		(fp_line
			(start -1.651 -1.651)
			(end -1.651 -1.317)
			(stroke
				(width 0.15)
				(type solid)
			)
			(layer "F.SilkS")
		)
		(fp_line
			(start 1.634 1.3)
			(end 1.634 1.634)
			(stroke
				(width 0.15)
				(type solid)
			)
			(layer "F.SilkS")
		)
		(fp_line
			(start -1.635 1.3)
			(end -1.635 1.634)
			(stroke
				(width 0.15)
				(type solid)
			)
			(layer "F.SilkS")
		)
		(fp_line
			(start -1.635 1.634)
			(end 1.634 1.634)
			(stroke
				(width 0.15)
				(type solid)
			)
			(layer "F.SilkS")
		)
		(fp_circle
			(center -1.9 -1.4)
			(end -1.85 -1.4)
			(stroke
				(width 0.15)
				(type solid)
			)
			(fill yes)
			(layer "F.SilkS")
		)
		(fp_rect
			(start -2 -1.8)
			(end 2 1.798)
			(stroke
				(width 0.05)
				(type solid)
			)
			(fill no)
			(layer "F.CrtYd")
		)
		(fp_line
			(start -1.6425 -1.4175)
			(end -1.4175 -1.6425)
			(stroke
				(width 0.15)
				(type solid)
			)
			(layer "F.Fab")
		)
		(fp_rect
			(start -1.651 -1.651)
			(end 1.648 1.648)
			(stroke
				(width 0.15)
				(type solid)
			)
			(fill no)
			(layer "F.Fab")
		)
		(pad "1" smd rect
			(at -1.436 -0.99 90)
			(size 0.99 0.405)
			(layers "F.Cu" "F.Mask" "F.Paste")
			(net 38 "VDC")
			(pinfunction "S")
			(pintype "passive")
		)
		(pad "2" smd rect
			(at -1.436 -0.332 90)
			(size 0.99 0.405)
			(layers "F.Cu" "F.Mask" "F.Paste")
			(net 38 "VDC")
			(pinfunction "S")
			(pintype "passive")
		)
		(pad "3" smd rect
			(at -1.436 0.33 90)
			(size 0.99 0.405)
			(layers "F.Cu" "F.Mask" "F.Paste")
			(net 38 "VDC")
			(pinfunction "S")
			(pintype "passive")
		)
		(pad "4" smd rect
			(at -1.436 0.988 90)
			(size 0.99 0.405)
			(layers "F.Cu" "F.Mask" "F.Paste")
			(net 365 "Net-(Q12-G)")
			(pinfunction "G")
			(pintype "passive")
		)
		(pad "5" smd custom
			(at 0.557 0 90)
			(size 1.725 2.235)
			(layers "F.Cu" "F.Mask" "F.Paste")
			(net 595 "/Supply/12V_aux_fused")
			(pinfunction "D")
			(pintype "passive")
			(zone_connect 2)
			(options
				(clearance outline)
				(anchor rect)
			)
			(primitives
				(gr_poly
					(pts
						(xy 0.8625 0.1275) (xy 0.8625 -0.1275) (xy 1.3725 -0.1275) (xy 1.3725 -0.5325) (xy 0.8625 -0.5325)
						(xy 0.8625 -0.7875) (xy 1.3725 -0.7875) (xy 1.3725 -1.195) (xy 0.6125 -1.195) (xy 0.6125 1.195)
						(xy 1.3725 1.195) (xy 1.3725 0.7875) (xy 0.8625 0.7875) (xy 0.8625 0.5325) (xy 1.3725 0.5325)
						(xy 1.3725 0.1275)
					)
					(width 0)
					(fill yes)
				)
			)
		)
	)
	(footprint "antmicro-footprints:SC70-3"
		(layer "F.Cu")
		(at 94.450501 122.926 90)
		(property "Reference" "Q8"
			(at 0 -1.6 90)
			(layer "F.SilkS")
			(hide yes)
			(effects
				(font
					(size 0.7 0.7)
					(thickness 0.15)
				)
				(justify left bottom)
			)
		)
		(property "Value" "BSS138PW,115"
			(at 0 2.3 90)
			(layer "F.Fab")
			(effects
				(font
					(size 0.7 0.7)
					(thickness 0.15)
				)
				(justify left bottom)
			)
		)
		(property "Datasheet" "https://assets.nexperia.com/documents/data-sheet/BSS138PW.pdf"
			(at 0 0 90)
			(layer "F.Fab")
			(hide yes)
			(effects
				(font
					(size 1.27 1.27)
					(thickness 0.15)
				)
			)
		)
		(property "Description" "Power MOSFET, N Channel, 60 V, 320 mA, 0.9 ohm, SOT-323, Surface Mount"
			(at 0 0 90)
			(layer "F.Fab")
			(hide yes)
			(effects
				(font
					(size 1.27 1.27)
					(thickness 0.15)
				)
			)
		)
		(property "Author" "Antmicro"
			(at 217.376501 28.475499 0)
			(layer "F.Fab")
			(hide yes)
			(effects
				(font
					(size 1 1)
					(thickness 0.15)
				)
			)
		)
		(property "License" "Apache-2.0"
			(at 217.376501 28.475499 0)
			(layer "F.Fab")
			(hide yes)
			(effects
				(font
					(size 1 1)
					(thickness 0.15)
				)
			)
		)
		(property "MPN" "BSS138PW,115"
			(at 217.376501 28.475499 0)
			(layer "F.Fab")
			(hide yes)
			(effects
				(font
					(size 1 1)
					(thickness 0.15)
				)
			)
		)
		(property "Manufacturer" "Nexperia"
			(at 217.376501 28.475499 0)
			(layer "F.Fab")
			(hide yes)
			(effects
				(font
					(size 1 1)
					(thickness 0.15)
				)
			)
		)
		(sheetname "/FPGA bank 14/")
		(sheetfile "fpga-bank-14.kicad_sch")
		(attr smd)
		(fp_line
			(start -0.3 -1)
			(end 0.627 -0.999)
			(stroke
				(width 0.15)
				(type solid)
			)
			(layer "F.SilkS")
		)
		(fp_line
			(start 0.627 -0.6)
			(end 0.627 -0.999)
			(stroke
				(width 0.15)
				(type solid)
			)
			(layer "F.SilkS")
		)
		(fp_line
			(start 0.627 0.6)
			(end 0.627 1.001)
			(stroke
				(width 0.15)
				(type solid)
			)
			(layer "F.SilkS")
		)
		(fp_line
			(start -0.3 1)
			(end 0.627 1.001)
			(stroke
				(width 0.15)
				(type solid)
			)
			(layer "F.SilkS")
		)
		(fp_line
			(start 0.9 -1.3)
			(end 0.9 -0.4)
			(stroke
				(width 0.05)
				(type solid)
			)
			(layer "F.CrtYd")
		)
		(fp_line
			(start -0.9 -1.3)
			(end 0.9 -1.3)
			(stroke
				(width 0.05)
				(type solid)
			)
			(layer "F.CrtYd")
		)
		(fp_line
			(start -0.9 -1.3)
			(end -0.9 -1)
			(stroke
				(width 0.05)
				(type solid)
			)
			(layer "F.CrtYd")
		)
		(fp_line
			(start -0.9 -1)
			(end -1.4 -1)
			(stroke
				(width 0.05)
				(type solid)
			)
			(layer "F.CrtYd")
		)
		(fp_line
			(start 1.4 -0.4)
			(end 1.4 0.4)
			(stroke
				(width 0.05)
				(type solid)
			)
			(layer "F.CrtYd")
		)
		(fp_line
			(start 0.9 -0.4)
			(end 1.4 -0.4)
			(stroke
				(width 0.05)
				(type solid)
			)
			(layer "F.CrtYd")
		)
		(fp_line
			(start 1.4 0.4)
			(end 0.9 0.4)
			(stroke
				(width 0.05)
				(type solid)
			)
			(layer "F.CrtYd")
		)
		(fp_line
			(start 0.9 0.4)
			(end 0.9 1.3)
			(stroke
				(width 0.05)
				(type solid)
			)
			(layer "F.CrtYd")
		)
		(fp_line
			(start -0.9 1)
			(end -1.4 1)
			(stroke
				(width 0.05)
				(type solid)
			)
			(layer "F.CrtYd")
		)
		(fp_line
			(start -1.4 1)
			(end -1.4 -1)
			(stroke
				(width 0.05)
				(type solid)
			)
			(layer "F.CrtYd")
		)
		(fp_line
			(start 0.9 1.3)
			(end -0.9 1.3)
			(stroke
				(width 0.05)
				(type solid)
			)
			(layer "F.CrtYd")
		)
		(fp_line
			(start -0.9 1.3)
			(end -0.9 1)
			(stroke
				(width 0.05)
				(type solid)
			)
			(layer "F.CrtYd")
		)
		(fp_rect
			(start -0.623 -0.999)
			(end 0.627 1.001)
			(stroke
				(width 0.15)
				(type solid)
			)
			(fill no)
			(layer "F.Fab")
		)
		(pad "1" smd rect
			(at -1.051 -0.65 180)
			(size 0.6 0.6)
			(layers "F.Cu" "F.Mask" "F.Paste")
			(net 622 "/FPGA bank 14/USR_LED5")
			(pinfunction "G")
			(pintype "input")
		)
		(pad "2" smd rect
			(at -1.051 0.65 180)
			(size 0.6 0.6)
			(layers "F.Cu" "F.Mask" "F.Paste")
			(net 1 "GND")
			(pinfunction "S")
			(pintype "passive")
		)
		(pad "3" smd rect
			(at 1.05 0 180)
			(size 0.6 0.6)
			(layers "F.Cu" "F.Mask" "F.Paste")
			(net 357 "Net-(Q8-D)")
			(pinfunction "D")
			(pintype "passive")
		)
	)
	(footprint "antmicro-footprints:R_0402_1005Metric"
		(layer "F.Cu")
		(at 191.775 195.335 90)
		(descr "Resistor SMD 0402")
		(tags "resistor SMD 0402")
		(property "Reference" "R180"
			(at -1.122484 -0.772697 90)
			(layer "F.SilkS")
			(hide yes)
			(effects
				(font
					(size 0.7 0.7)
					(thickness 0.15)
				)
				(justify left bottom)
			)
		)
		(property "Value" "R_4k7_0402"
			(at -1.011843 1.772047 90)
			(layer "F.Fab")
			(effects
				(font
					(size 0.7 0.7)
					(thickness 0.15)
				)
				(justify left bottom)
			)
		)
		(property "Datasheet" "https://www.bourns.com/docs/product-datasheets/cr.pdf"
			(at 0 0 90)
			(layer "F.Fab")
			(hide yes)
			(effects
				(font
					(size 1.27 1.27)
					(thickness 0.15)
				)
			)
		)
		(property "Author" "Antmicro"
			(at 387.11 3.56 0)
			(layer "F.Fab")
			(hide yes)
			(effects
				(font
					(size 1 1)
					(thickness 0.15)
				)
			)
		)
		(property "License" "Apache-2.0"
			(at 387.11 3.56 0)
			(layer "F.Fab")
			(hide yes)
			(effects
				(font
					(size 1 1)
					(thickness 0.15)
				)
			)
		)
		(property "MPN" "CR0402-FX-4701GLF"
			(at 387.11 3.56 0)
			(layer "F.Fab")
			(hide yes)
			(effects
				(font
					(size 1 1)
					(thickness 0.15)
				)
			)
		)
		(property "Manufacturer" "Bourns"
			(at 387.11 3.56 0)
			(layer "F.Fab")
			(hide yes)
			(effects
				(font
					(size 1 1)
					(thickness 0.15)
				)
			)
		)
		(property "Tolerance" "1%"
			(at 387.11 3.56 0)
			(layer "F.Fab")
			(hide yes)
			(effects
				(font
					(size 1 1)
					(thickness 0.15)
				)
			)
		)
		(property "Val" "4k7"
			(at 387.11 3.56 0)
			(layer "F.Fab")
			(hide yes)
			(effects
				(font
					(size 1 1)
					(thickness 0.15)
				)
			)
		)
		(sheetname "/Supply/")
		(sheetfile "supply.kicad_sch")
		(attr smd)
		(fp_rect
			(start -0.93 -0.47)
			(end 0.93 0.47)
			(stroke
				(width 0.05)
				(type solid)
			)
			(fill no)
			(layer "F.CrtYd")
		)
		(fp_rect
			(start -0.5 -0.25)
			(end 0.5 0.25)
			(stroke
				(width 0.15)
				(type solid)
			)
			(fill no)
			(layer "F.Fab")
		)
		(pad "1" smd roundrect
			(at -0.485 0 90)
			(size 0.59 0.64)
			(layers "F.Cu" "F.Mask" "F.Paste")
			(roundrect_rratio 0.25)
			(net 1 "GND")
			(pintype "passive")
		)
		(pad "2" smd roundrect
			(at 0.485 0 90)
			(size 0.59 0.64)
			(layers "F.Cu" "F.Mask" "F.Paste")
			(roundrect_rratio 0.25)
			(net 224 "/Supply/MGTAVTT_ILIM")
			(pintype "passive")
		)
	)
	(footprint "antmicro-footprints:LED_0603_1608Metric_G"
		(layer "F.Cu")
		(at 83.650501 116.426 -90)
		(descr "LED SMD 0603 Green")
		(tags "LED SMD 0603 Green")
		(property "Reference" "D4"
			(at -0.001 -0.901 270)
			(layer "F.SilkS")
			(hide yes)
			(effects
				(font
					(size 0.7 0.7)
					(thickness 0.15)
				)
				(justify left bottom)
			)
		)
		(property "Value" "LED_G_0603_KP-1608CGCK"
			(at -0.001 1.599 270)
			(layer "F.Fab")
			(effects
				(font
					(size 0.7 0.7)
					(thickness 0.15)
				)
				(justify left bottom)
			)
		)
		(property "Datasheet" "http://www.farnell.com/datasheets/2045956.pdf"
			(at 0 0 270)
			(layer "F.Fab")
			(hide yes)
			(effects
				(font
					(size 1.27 1.27)
					(thickness 0.15)
				)
			)
		)
		(property "Author" "Antmicro"
			(at -32.775499 200.076501 0)
			(layer "F.Fab")
			(hide yes)
			(effects
				(font
					(size 1 1)
					(thickness 0.15)
				)
			)
		)
		(property "License" "Apache-2.0"
			(at -32.775499 200.076501 0)
			(layer "F.Fab")
			(hide yes)
			(effects
				(font
					(size 1 1)
					(thickness 0.15)
				)
			)
		)
		(property "MPN" "KP-1608CGCK"
			(at -32.775499 200.076501 0)
			(layer "F.Fab")
			(hide yes)
			(effects
				(font
					(size 1 1)
					(thickness 0.15)
				)
			)
		)
		(property "Manufacturer" "Kingbright"
			(at -32.775499 200.076501 0)
			(layer "F.Fab")
			(hide yes)
			(effects
				(font
					(size 1 1)
					(thickness 0.15)
				)
			)
		)
		(sheetname "/FPGA bank 14/")
		(sheetfile "fpga-bank-14.kicad_sch")
		(attr smd)
		(fp_line
			(start -0.271 0.348)
			(end 0.269 0.348)
			(stroke
				(width 0.15)
				(type solid)
			)
			(layer "F.SilkS")
		)
		(fp_line
			(start 1.249 0.319)
			(end 1.249 -0.321)
			(stroke
				(width 0.15)
				(type solid)
			)
			(layer "F.SilkS")
		)
		(fp_line
			(start -0.107 -0.001)
			(end -0.291 -0.001)
			(stroke
				(width 0.1)
				(type solid)
			)
			(layer "F.SilkS")
		)
		(fp_line
			(start 0.092 -0.001)
			(end -0.107 0.198)
			(stroke
				(width 0.1)
				(type solid)
			)
			(layer "F.SilkS")
		)
		(fp_line
			(start 0.092 -0.001)
			(end 0.292 -0.001)
			(stroke
				(width 0.1)
				(type solid)
			)
			(layer "F.SilkS")
		)
		(fp_line
			(start -0.107 -0.201)
			(end -0.107 0.198)
			(stroke
				(width 0.1)
				(type solid)
			)
			(layer "F.SilkS")
		)
		(fp_line
			(start -0.107 -0.201)
			(end 0.092 -0.001)
			(stroke
				(width 0.1)
				(type solid)
			)
			(layer "F.SilkS")
		)
		(fp_line
			(start 0.092 -0.201)
			(end 0.092 0.198)
			(stroke
				(width 0.1)
				(type solid)
			)
			(layer "F.SilkS")
		)
		(fp_line
			(start -0.271 -0.349)
			(end 0.269 -0.349)
			(stroke
				(width 0.15)
				(type solid)
			)
			(layer "F.SilkS")
		)
		(fp_rect
			(start -1.2192 -0.6096)
			(end 1.27 0.6016)
			(stroke
				(width 0.05)
				(type solid)
			)
			(fill no)
			(layer "F.CrtYd")
		)
		(fp_line
			(start -0.202 0.201)
			(end 0.1 -0.001)
			(stroke
				(width 0.15)
				(type solid)
			)
			(layer "F.Fab")
		)
		(fp_line
			(start 0.198 0.201)
			(end 0.198 -0.101)
			(stroke
				(width 0.15)
				(type solid)
			)
			(layer "F.Fab")
		)
		(fp_line
			(start -0.849 0.025)
			(end -0.442 0.381)
			(stroke
				(width 0.15)
				(type solid)
			)
			(layer "F.Fab")
		)
		(fp_line
			(start -0.6 -0.001)
			(end -0.202 -0.001)
			(stroke
				(width 0.15)
				(type solid)
			)
			(layer "F.Fab")
		)
		(fp_line
			(start -0.202 -0.001)
			(end -0.202 0.201)
			(stroke
				(width 0.15)
				(type solid)
			)
			(layer "F.Fab")
		)
		(fp_line
			(start 0.1 -0.001)
			(end -0.202 -0.201)
			(stroke
				(width 0.15)
				(type solid)
			)
			(layer "F.Fab")
		)
		(fp_line
			(start 0.198 -0.001)
			(end 0.596 -0.001)
			(stroke
				(width 0.15)
				(type solid)
			)
			(layer "F.Fab")
		)
		(fp_line
			(start -0.202 -0.201)
			(end -0.202 -0.001)
			(stroke
				(width 0.15)
				(type solid)
			)
			(layer "F.Fab")
		)
		(fp_line
			(start 0.198 -0.201)
			(end 0.198 -0.101)
			(stroke
				(width 0.15)
				(type solid)
			)
			(layer "F.Fab")
		)
		(fp_rect
			(start -0.849 -0.401)
			(end 0.849 0.401)
			(stroke
				(width 0.15)
				(type solid)
			)
			(fill no)
			(layer "F.Fab")
		)
		(pad "1" smd rect
			(at -0.751 -0.001 90)
			(size 0.8 0.8)
			(layers "F.Cu" "F.Mask" "F.Paste")
			(net 200 "+3V3")
			(pinfunction "1")
			(pintype "passive")
		)
		(pad "2" smd rect
			(at 0.749 -0.001 90)
			(size 0.8 0.8)
			(layers "F.Cu" "F.Mask" "F.Paste")
			(net 307 "Net-(D4-Pad2)")
			(pinfunction "2")
			(pintype "passive")
		)
	)
	(footprint "antmicro-footprints:R_0402_1005Metric"
		(layer "F.Cu")
		(at 91.750501 119.926 -90)
		(descr "Resistor SMD 0402")
		(tags "resistor SMD 0402")
		(property "Reference" "R45"
			(at -1.122484 -0.772697 270)
			(layer "F.SilkS")
			(hide yes)
			(effects
				(font
					(size 0.7 0.7)
					(thickness 0.15)
				)
				(justify left bottom)
			)
		)
		(property "Value" "R_330R_0402"
			(at -1.011843 1.772047 270)
			(layer "F.Fab")
			(effects
				(font
					(size 0.7 0.7)
					(thickness 0.15)
				)
				(justify left bottom)
			)
		)
		(property "Datasheet" "https://www.bourns.com/docs/product-datasheets/cr.pdf"
			(at 0 0 270)
			(layer "F.Fab")
			(hide yes)
			(effects
				(font
					(size 1.27 1.27)
					(thickness 0.15)
				)
			)
		)
		(property "Author" "Antmicro"
			(at -28.175499 211.676501 0)
			(layer "F.Fab")
			(hide yes)
			(effects
				(font
					(size 1 1)
					(thickness 0.15)
				)
			)
		)
		(property "License" "Apache-2.0"
			(at -28.175499 211.676501 0)
			(layer "F.Fab")
			(hide yes)
			(effects
				(font
					(size 1 1)
					(thickness 0.15)
				)
			)
		)
		(property "MPN" "CR0402-FX-3300GLF"
			(at -28.175499 211.676501 0)
			(layer "F.Fab")
			(hide yes)
			(effects
				(font
					(size 1 1)
					(thickness 0.15)
				)
			)
		)
		(property "Manufacturer" "Bourns"
			(at -28.175499 211.676501 0)
			(layer "F.Fab")
			(hide yes)
			(effects
				(font
					(size 1 1)
					(thickness 0.15)
				)
			)
		)
		(property "Tolerance" "1%"
			(at -28.175499 211.676501 0)
			(layer "F.Fab")
			(hide yes)
			(effects
				(font
					(size 1 1)
					(thickness 0.15)
				)
			)
		)
		(property "Val" "330R"
			(at -28.175499 211.676501 0)
			(layer "F.Fab")
			(hide yes)
			(effects
				(font
					(size 1 1)
					(thickness 0.15)
				)
			)
		)
		(sheetname "/FPGA bank 14/")
		(sheetfile "fpga-bank-14.kicad_sch")
		(attr smd)
		(fp_rect
			(start -0.93 -0.47)
			(end 0.93 0.47)
			(stroke
				(width 0.05)
				(type solid)
			)
			(fill no)
			(layer "F.CrtYd")
		)
		(fp_rect
			(start -0.5 -0.25)
			(end 0.5 0.25)
			(stroke
				(width 0.15)
				(type solid)
			)
			(fill no)
			(layer "F.Fab")
		)
		(pad "1" smd roundrect
			(at -0.485 0 270)
			(size 0.59 0.64)
			(layers "F.Cu" "F.Mask" "F.Paste")
			(roundrect_rratio 0.25)
			(net 310 "Net-(D7-Pad2)")
			(pintype "passive")
		)
		(pad "2" smd roundrect
			(at 0.485 0 270)
			(size 0.59 0.64)
			(layers "F.Cu" "F.Mask" "F.Paste")
			(roundrect_rratio 0.25)
			(net 356 "Net-(Q7-D)")
			(pintype "passive")
		)
	)
)
